# T6G (Grand Teton) — schematic netlist excerpt (pin names and nets, part order shuffled) for the footprints in the layout excerpt that follows; sources: Cadence DE-HDL packaged netlist, KiCad conversion of 04192023_DAF0TMB3IC0_F0TG_MB_C_brd_V02_OCP.brd

R150  Q_RES  0 5% EMPTY  pkg 0402LF  page 160 : A = SMB_CPU0_CPU1_APML_SDA ; B = SMB_CPU0_CPU1_APML_BUF1_SDA
R6028  Q_RES  0 5% CHIP  pkg 0402LF  page 150 : A = FM_LPC_ESPI_SEL ; B = GND

(kicad_pcb
	(version 20260206)
	(generator "pcbnew")
	(generator_version "10.0")
	(general
		(thickness 1.6)
		(legacy_teardrops no)
	)
	(paper "A4")
	(title_block
		(title "04192023_DAF0TMB3IC0_F0TG_MB_C_brd_V02_OCP.brd")
		(comment 1 "Grand Teton / footprints 7930-7931 of 8354")
	)
	(layers
		(0 "F.Cu" signal "TOP")
		(4 "In1.Cu" signal "GND")
		(6 "In2.Cu" signal "IN1")
		(8 "In3.Cu" signal "GND1")
		(10 "In4.Cu" signal "IN2")
		(12 "In5.Cu" signal "GND2")
		(14 "In6.Cu" signal "IN3")
		(16 "In7.Cu" signal "GND3")
		(18 "In8.Cu" signal "VCC")
		(20 "In9.Cu" signal "VCC1")
		(22 "In10.Cu" signal "GND4")
		(24 "In11.Cu" signal "IN4")
		(26 "In12.Cu" signal "GND5")
		(28 "In13.Cu" signal "IN5")
		(30 "In14.Cu" signal "GND6")
		(32 "In15.Cu" signal "IN6")
		(34 "In16.Cu" signal "GND7")
		(2 "B.Cu" signal "BOTTOM")
		(9 "F.Adhes" user "F.Adhesive")
		(11 "B.Adhes" user "B.Adhesive")
		(13 "F.Paste" user "Package Geometry/Pastemask Top")
		(15 "B.Paste" user "Package Geometry/Pastemask Bottom")
		(5 "F.SilkS" user "Ref Des/Silkscreen Top")
		(7 "B.SilkS" user "Ref Des/Silkscreen Bottom")
		(1 "F.Mask" user "Board Geometry/Soldermask Top")
		(3 "B.Mask" user "Board Geometry/Soldermask Bottom")
		(17 "Dwgs.User" user "User.Drawings")
		(19 "Cmts.User" user "User.Comments")
		(21 "Eco1.User" user "User.Eco1")
		(23 "Eco2.User" user "User.Eco2")
		(25 "Edge.Cuts" user "Board Geometry/Outline")
		(27 "Margin" user)
		(31 "F.CrtYd" user "Package Geometry/Place Bound Top")
		(29 "B.CrtYd" user "Package Geometry/Place Bound Bottom")
		(35 "F.Fab" user "Ref Des/Assembly Top")
		(33 "B.Fab" user "Ref Des/Assembly Bottom")
	)
	(footprint ""
		(layer "B.Cu")
		(at 173.213776 -19.209258)
		(property "Reference" "R6028"
			(at 0 0 0)
			(layer "B.SilkS")
			(hide yes)
			(effects
				(font
					(size 1.27 1.27)
				)
				(justify mirror)
			)
		)
		(property "Value" ""
			(at 0 0 0)
			(layer "B.Fab")
			(effects
				(font
					(size 1.27 1.27)
				)
				(justify mirror)
			)
		)
		(duplicate_pad_numbers_are_jumpers no)
		(fp_line
			(start -0.7874 -0.4064)
			(end -0.7874 0.4064)
			(stroke
				(width 0.1524)
				(type default)
			)
			(layer "B.SilkS")
		)
		(fp_line
			(start -0.7874 0.4064)
			(end 0.7874 0.4064)
			(stroke
				(width 0.1524)
				(type default)
			)
			(layer "B.SilkS")
		)
		(fp_line
			(start 0.7874 -0.4064)
			(end -0.7874 -0.4064)
			(stroke
				(width 0.1524)
				(type default)
			)
			(layer "B.SilkS")
		)
		(fp_line
			(start 0.7874 0.4064)
			(end 0.7874 -0.4064)
			(stroke
				(width 0.1524)
				(type default)
			)
			(layer "B.SilkS")
		)
		(fp_line
			(start -0.67945 -0.3048)
			(end -0.67945 0.3048)
			(stroke
				(width 0.1)
				(type default)
			)
			(layer "B.Fab")
		)
		(fp_line
			(start -0.67945 0.3048)
			(end -0.120396 0.3048)
			(stroke
				(width 0.1)
				(type default)
			)
			(layer "B.Fab")
		)
		(fp_line
			(start -0.12065 -0.3048)
			(end -0.67945 -0.3048)
			(stroke
				(width 0.1)
				(type default)
			)
			(layer "B.Fab")
		)
		(fp_line
			(start -0.12065 -0.2794)
			(end -0.12065 -0.3048)
			(stroke
				(width 0.1)
				(type default)
			)
			(layer "B.Fab")
		)
		(fp_line
			(start -0.120396 0.2794)
			(end 0.12065 0.2794)
			(stroke
				(width 0.1)
				(type default)
			)
			(layer "B.Fab")
		)
		(fp_line
			(start -0.120396 0.3048)
			(end -0.120396 0.2794)
			(stroke
				(width 0.1)
				(type default)
			)
			(layer "B.Fab")
		)
		(fp_line
			(start 0.12065 -0.305054)
			(end 0.12065 -0.2794)
			(stroke
				(width 0.1)
				(type default)
			)
			(layer "B.Fab")
		)
		(fp_line
			(start 0.12065 -0.2794)
			(end -0.12065 -0.2794)
			(stroke
				(width 0.1)
				(type default)
			)
			(layer "B.Fab")
		)
		(fp_line
			(start 0.12065 0.2794)
			(end 0.12065 0.3048)
			(stroke
				(width 0.1)
				(type default)
			)
			(layer "B.Fab")
		)
		(fp_line
			(start 0.12065 0.3048)
			(end 0.67945 0.3048)
			(stroke
				(width 0.1)
				(type default)
			)
			(layer "B.Fab")
		)
		(fp_line
			(start 0.67945 -0.305054)
			(end 0.12065 -0.305054)
			(stroke
				(width 0.1)
				(type default)
			)
			(layer "B.Fab")
		)
		(fp_line
			(start 0.67945 0.3048)
			(end 0.67945 -0.305054)
			(stroke
				(width 0.1)
				(type default)
			)
			(layer "B.Fab")
		)
		(pad "1" smd circle
			(at 0.40005 0 180)
			(size 0 0)
			(layers "B.Cu" "B.Mask" "B.Paste")
			(net "FM_LPC_ESPI_SEL")
		)
		(pad "2" smd circle
			(at -0.40005 0 180)
			(size 0 0)
			(layers "B.Cu" "B.Mask" "B.Paste")
			(net "GND")
		)
	)
	(footprint ""
		(layer "B.Cu")
		(at 234.4801 -228.092 180)
		(property "Reference" "R150"
			(at 0 0 0)
			(layer "B.SilkS")
			(hide yes)
			(effects
				(font
					(size 1.27 1.27)
				)
				(justify mirror)
			)
		)
		(property "Value" ""
			(at 0 0 0)
			(layer "B.Fab")
			(effects
				(font
					(size 1.27 1.27)
				)
				(justify mirror)
			)
		)
		(duplicate_pad_numbers_are_jumpers no)
		(fp_line
			(start 0.7874 0.4064)
			(end 0.7874 -0.4064)
			(stroke
				(width 0.1524)
				(type default)
			)
			(layer "B.SilkS")
		)
		(fp_line
			(start 0.7874 -0.4064)
			(end -0.7874 -0.4064)
			(stroke
				(width 0.1524)
				(type default)
			)
			(layer "B.SilkS")
		)
		(fp_line
			(start -0.7874 0.4064)
			(end 0.7874 0.4064)
			(stroke
				(width 0.1524)
				(type default)
			)
			(layer "B.SilkS")
		)
		(fp_line
			(start -0.7874 -0.4064)
			(end -0.7874 0.4064)
			(stroke
				(width 0.1524)
				(type default)
			)
			(layer "B.SilkS")
		)
		(fp_line
			(start 0.67945 0.3048)
			(end 0.67945 -0.305054)
			(stroke
				(width 0.1)
				(type default)
			)
			(layer "B.Fab")
		)
		(fp_line
			(start 0.67945 -0.305054)
			(end 0.12065 -0.305054)
			(stroke
				(width 0.1)
				(type default)
			)
			(layer "B.Fab")
		)
		(fp_line
			(start 0.12065 0.3048)
			(end 0.67945 0.3048)
			(stroke
				(width 0.1)
				(type default)
			)
			(layer "B.Fab")
		)
		(fp_line
			(start 0.12065 0.2794)
			(end 0.12065 0.3048)
			(stroke
				(width 0.1)
				(type default)
			)
			(layer "B.Fab")
		)
		(fp_line
			(start 0.12065 -0.2794)
			(end -0.12065 -0.2794)
			(stroke
				(width 0.1)
				(type default)
			)
			(layer "B.Fab")
		)
		(fp_line
			(start 0.12065 -0.305054)
			(end 0.12065 -0.2794)
			(stroke
				(width 0.1)
				(type default)
			)
			(layer "B.Fab")
		)
		(fp_line
			(start -0.120396 0.3048)
			(end -0.120396 0.2794)
			(stroke
				(width 0.1)
				(type default)
			)
			(layer "B.Fab")
		)
		(fp_line
			(start -0.120396 0.2794)
			(end 0.12065 0.2794)
			(stroke
				(width 0.1)
				(type default)
			)
			(layer "B.Fab")
		)
		(fp_line
			(start -0.12065 -0.2794)
			(end -0.12065 -0.3048)
			(stroke
				(width 0.1)
				(type default)
			)
			(layer "B.Fab")
		)
		(fp_line
			(start -0.12065 -0.3048)
			(end -0.67945 -0.3048)
			(stroke
				(width 0.1)
				(type default)
			)
			(layer "B.Fab")
		)
		(fp_line
			(start -0.67945 0.3048)
			(end -0.120396 0.3048)
			(stroke
				(width 0.1)
				(type default)
			)
			(layer "B.Fab")
		)
		(fp_line
			(start -0.67945 -0.3048)
			(end -0.67945 0.3048)
			(stroke
				(width 0.1)
				(type default)
			)
			(layer "B.Fab")
		)
		(pad "1" smd rect
			(at 0.40005 0 180)
			(size 0.4572 0.508)
			(layers "B.Cu" "B.Mask" "B.Paste")
			(net "SMB_CPU0_CPU1_APML_SDA")
		)
		(pad "2" smd rect
			(at -0.40005 0 180)
			(size 0.4572 0.508)
			(layers "B.Cu" "B.Mask" "B.Paste")
			(net "SMB_CPU0_CPU1_APML_BUF1_SDA")
		)
	)
)
